(kicad_pcb
	(version 20260206)
	(generator "pcbnew")
	(generator_version "10.0")
	(general
		(thickness 1.6)
		(legacy_teardrops no)
	)
	(paper "A4")
	(title_block
		(title "03242023_DA0F0TMBIJ0_F0T_Motherboard_J_brd_V01_OCP.brd")
		(comment 1 "Grand Teton / footprints 4191-4197 of 6105")
	)
	(layers
		(0 "F.Cu" signal "TOP")
		(4 "In1.Cu" signal "GND")
		(6 "In2.Cu" signal "IN1")
		(8 "In3.Cu" signal "GND1")
		(10 "In4.Cu" signal "IN2")
		(12 "In5.Cu" signal "GND2")
		(14 "In6.Cu" signal "IN3")
		(16 "In7.Cu" signal "GND3")
		(18 "In8.Cu" signal "VCC")
		(20 "In9.Cu" signal "VCC1")
		(22 "In10.Cu" signal "GND4")
		(24 "In11.Cu" signal "IN4")
		(26 "In12.Cu" signal "GND5")
		(28 "In13.Cu" signal "IN5")
		(30 "In14.Cu" signal "GND6")
		(32 "In15.Cu" signal "IN6")
		(34 "In16.Cu" signal "GND7")
		(2 "B.Cu" signal "BOTTOM")
		(9 "F.Adhes" user "F.Adhesive")
		(11 "B.Adhes" user "B.Adhesive")
		(13 "F.Paste" user "Package Geometry/Pastemask Top")
		(15 "B.Paste" user "Package Geometry/Pastemask Bottom")
		(5 "F.SilkS" user "Ref Des/Silkscreen Top")
		(7 "B.SilkS" user "Ref Des/Silkscreen Bottom")
		(1 "F.Mask" user "Board Geometry/Soldermask Top")
		(3 "B.Mask" user "Board Geometry/Soldermask Bottom")
		(17 "Dwgs.User" user "User.Drawings")
		(19 "Cmts.User" user "User.Comments")
		(21 "Eco1.User" user "User.Eco1")
		(23 "Eco2.User" user "User.Eco2")
		(25 "Edge.Cuts" user "Board Geometry/Outline")
		(27 "Margin" user)
		(31 "F.CrtYd" user "Package Geometry/Place Bound Top")
		(29 "B.CrtYd" user "Package Geometry/Place Bound Bottom")
		(35 "F.Fab" user "Ref Des/Assembly Top")
		(33 "B.Fab" user "Ref Des/Assembly Bottom")
	)
	(footprint ""
		(layer "B.Cu")
		(at 336.17408 -43.504358)
		(property "Reference" "C1203"
			(at 0 0 0)
			(layer "B.SilkS")
			(hide yes)
			(effects
				(font
					(size 1.27 1.27)
				)
				(justify mirror)
			)
		)
		(property "Value" ""
			(at 0 0 0)
			(layer "B.Fab")
			(effects
				(font
					(size 1.27 1.27)
				)
				(justify mirror)
			)
		)
		(duplicate_pad_numbers_are_jumpers no)
		(fp_line
			(start -0.7874 -0.4064)
			(end -0.7874 0.4064)
			(stroke
				(width 0.1524)
				(type default)
			)
			(layer "B.SilkS")
		)
		(fp_line
			(start -0.7874 0.4064)
			(end 0.7874 0.4064)
			(stroke
				(width 0.1524)
				(type default)
			)
			(layer "B.SilkS")
		)
		(fp_line
			(start 0.7874 -0.4064)
			(end -0.7874 -0.4064)
			(stroke
				(width 0.1524)
				(type default)
			)
			(layer "B.SilkS")
		)
		(fp_line
			(start 0.7874 0.4064)
			(end 0.7874 -0.4064)
			(stroke
				(width 0.1524)
				(type default)
			)
			(layer "B.SilkS")
		)
		(fp_line
			(start -0.67945 -0.3048)
			(end -0.67945 0.3048)
			(stroke
				(width 0.1)
				(type default)
			)
			(layer "B.Fab")
		)
		(fp_line
			(start -0.67945 0.3048)
			(end -0.120396 0.3048)
			(stroke
				(width 0.1)
				(type default)
			)
			(layer "B.Fab")
		)
		(fp_line
			(start -0.12065 -0.3048)
			(end -0.67945 -0.3048)
			(stroke
				(width 0.1)
				(type default)
			)
			(layer "B.Fab")
		)
		(fp_line
			(start -0.12065 -0.2794)
			(end -0.12065 -0.3048)
			(stroke
				(width 0.1)
				(type default)
			)
			(layer "B.Fab")
		)
		(fp_line
			(start -0.120396 0.2794)
			(end 0.12065 0.2794)
			(stroke
				(width 0.1)
				(type default)
			)
			(layer "B.Fab")
		)
		(fp_line
			(start -0.120396 0.3048)
			(end -0.120396 0.2794)
			(stroke
				(width 0.1)
				(type default)
			)
			(layer "B.Fab")
		)
		(fp_line
			(start 0.12065 -0.305054)
			(end 0.12065 -0.2794)
			(stroke
				(width 0.1)
				(type default)
			)
			(layer "B.Fab")
		)
		(fp_line
			(start 0.12065 -0.2794)
			(end -0.12065 -0.2794)
			(stroke
				(width 0.1)
				(type default)
			)
			(layer "B.Fab")
		)
		(fp_line
			(start 0.12065 0.2794)
			(end 0.12065 0.3048)
			(stroke
				(width 0.1)
				(type default)
			)
			(layer "B.Fab")
		)
		(fp_line
			(start 0.12065 0.3048)
			(end 0.67945 0.3048)
			(stroke
				(width 0.1)
				(type default)
			)
			(layer "B.Fab")
		)
		(fp_line
			(start 0.67945 -0.305054)
			(end 0.12065 -0.305054)
			(stroke
				(width 0.1)
				(type default)
			)
			(layer "B.Fab")
		)
		(fp_line
			(start 0.67945 0.3048)
			(end 0.67945 -0.305054)
			(stroke
				(width 0.1)
				(type default)
			)
			(layer "B.Fab")
		)
		(pad "1" smd circle
			(at 0.40005 0 180)
			(size 0 0)
			(layers "B.Cu" "B.Mask" "B.Paste")
			(net "P1V05_PCH_AUX")
		)
		(pad "2" smd circle
			(at -0.40005 0 180)
			(size 0 0)
			(layers "B.Cu" "B.Mask" "B.Paste")
			(net "GND")
		)
	)
	(footprint ""
		(layer "B.Cu")
		(at 80.763618 -188.552836 -90)
		(property "Reference" "R49"
			(at 0 0 90)
			(layer "B.SilkS")
			(hide yes)
			(effects
				(font
					(size 1.27 1.27)
				)
				(justify mirror)
			)
		)
		(property "Value" ""
			(at 0 0 90)
			(layer "B.Fab")
			(effects
				(font
					(size 1.27 1.27)
				)
				(justify mirror)
			)
		)
		(duplicate_pad_numbers_are_jumpers no)
		(fp_line
			(start -0.7874 0.4064)
			(end 0.7874 0.4064)
			(stroke
				(width 0.1524)
				(type default)
			)
			(layer "B.SilkS")
		)
		(fp_line
			(start 0.7874 0.4064)
			(end 0.7874 -0.4064)
			(stroke
				(width 0.1524)
				(type default)
			)
			(layer "B.SilkS")
		)
		(fp_line
			(start -0.7874 -0.4064)
			(end -0.7874 0.4064)
			(stroke
				(width 0.1524)
				(type default)
			)
			(layer "B.SilkS")
		)
		(fp_line
			(start 0.7874 -0.4064)
			(end -0.7874 -0.4064)
			(stroke
				(width 0.1524)
				(type default)
			)
			(layer "B.SilkS")
		)
		(fp_line
			(start -0.67945 0.3048)
			(end -0.120396 0.3048)
			(stroke
				(width 0.1)
				(type default)
			)
			(layer "B.Fab")
		)
		(fp_line
			(start -0.120396 0.3048)
			(end -0.120396 0.2794)
			(stroke
				(width 0.1)
				(type default)
			)
			(layer "B.Fab")
		)
		(fp_line
			(start 0.12065 0.3048)
			(end 0.67945 0.3048)
			(stroke
				(width 0.1)
				(type default)
			)
			(layer "B.Fab")
		)
		(fp_line
			(start 0.67945 0.3048)
			(end 0.67945 -0.305054)
			(stroke
				(width 0.1)
				(type default)
			)
			(layer "B.Fab")
		)
		(fp_line
			(start -0.120396 0.2794)
			(end 0.12065 0.2794)
			(stroke
				(width 0.1)
				(type default)
			)
			(layer "B.Fab")
		)
		(fp_line
			(start 0.12065 0.2794)
			(end 0.12065 0.3048)
			(stroke
				(width 0.1)
				(type default)
			)
			(layer "B.Fab")
		)
		(fp_line
			(start -0.12065 -0.2794)
			(end -0.12065 -0.3048)
			(stroke
				(width 0.1)
				(type default)
			)
			(layer "B.Fab")
		)
		(fp_line
			(start 0.12065 -0.2794)
			(end -0.12065 -0.2794)
			(stroke
				(width 0.1)
				(type default)
			)
			(layer "B.Fab")
		)
		(fp_line
			(start -0.67945 -0.3048)
			(end -0.67945 0.3048)
			(stroke
				(width 0.1)
				(type default)
			)
			(layer "B.Fab")
		)
		(fp_line
			(start -0.12065 -0.3048)
			(end -0.67945 -0.3048)
			(stroke
				(width 0.1)
				(type default)
			)
			(layer "B.Fab")
		)
		(fp_line
			(start 0.12065 -0.305054)
			(end 0.12065 -0.2794)
			(stroke
				(width 0.1)
				(type default)
			)
			(layer "B.Fab")
		)
		(fp_line
			(start 0.67945 -0.305054)
			(end 0.12065 -0.305054)
			(stroke
				(width 0.1)
				(type default)
			)
			(layer "B.Fab")
		)
		(pad "1" smd circle
			(at 0.40005 0 90)
			(size 0 0)
			(layers "B.Cu" "B.Mask" "B.Paste")
			(net "PVNN_TERM_CPU1")
		)
		(pad "2" smd circle
			(at -0.40005 0 90)
			(size 0 0)
			(layers "B.Cu" "B.Mask" "B.Paste")
			(net "DBP_CPU_MBP0_GTL_N")
		)
	)
	(footprint ""
		(layer "B.Cu")
		(at 436.941214 -319.263776 180)
		(property "Reference" "C41"
			(at 0 0 0)
			(layer "B.SilkS")
			(hide yes)
			(effects
				(font
					(size 1.27 1.27)
				)
				(justify mirror)
			)
		)
		(property "Value" ""
			(at 0 0 0)
			(layer "B.Fab")
			(effects
				(font
					(size 1.27 1.27)
				)
				(justify mirror)
			)
		)
		(duplicate_pad_numbers_are_jumpers no)
		(fp_line
			(start 0.7874 0.4064)
			(end 0.7874 -0.4064)
			(stroke
				(width 0.1524)
				(type default)
			)
			(layer "B.SilkS")
		)
		(fp_line
			(start 0.7874 -0.4064)
			(end -0.7874 -0.4064)
			(stroke
				(width 0.1524)
				(type default)
			)
			(layer "B.SilkS")
		)
		(fp_line
			(start -0.7874 0.4064)
			(end 0.7874 0.4064)
			(stroke
				(width 0.1524)
				(type default)
			)
			(layer "B.SilkS")
		)
		(fp_line
			(start -0.7874 -0.4064)
			(end -0.7874 0.4064)
			(stroke
				(width 0.1524)
				(type default)
			)
			(layer "B.SilkS")
		)
		(fp_line
			(start 0.67945 0.3048)
			(end 0.67945 -0.305054)
			(stroke
				(width 0.1)
				(type default)
			)
			(layer "B.Fab")
		)
		(fp_line
			(start 0.67945 -0.305054)
			(end 0.12065 -0.305054)
			(stroke
				(width 0.1)
				(type default)
			)
			(layer "B.Fab")
		)
		(fp_line
			(start 0.12065 0.3048)
			(end 0.67945 0.3048)
			(stroke
				(width 0.1)
				(type default)
			)
			(layer "B.Fab")
		)
		(fp_line
			(start 0.12065 0.2794)
			(end 0.12065 0.3048)
			(stroke
				(width 0.1)
				(type default)
			)
			(layer "B.Fab")
		)
		(fp_line
			(start 0.12065 -0.2794)
			(end -0.12065 -0.2794)
			(stroke
				(width 0.1)
				(type default)
			)
			(layer "B.Fab")
		)
		(fp_line
			(start 0.12065 -0.305054)
			(end 0.12065 -0.2794)
			(stroke
				(width 0.1)
				(type default)
			)
			(layer "B.Fab")
		)
		(fp_line
			(start -0.120396 0.3048)
			(end -0.120396 0.2794)
			(stroke
				(width 0.1)
				(type default)
			)
			(layer "B.Fab")
		)
		(fp_line
			(start -0.120396 0.2794)
			(end 0.12065 0.2794)
			(stroke
				(width 0.1)
				(type default)
			)
			(layer "B.Fab")
		)
		(fp_line
			(start -0.12065 -0.2794)
			(end -0.12065 -0.3048)
			(stroke
				(width 0.1)
				(type default)
			)
			(layer "B.Fab")
		)
		(fp_line
			(start -0.12065 -0.3048)
			(end -0.67945 -0.3048)
			(stroke
				(width 0.1)
				(type default)
			)
			(layer "B.Fab")
		)
		(fp_line
			(start -0.67945 0.3048)
			(end -0.120396 0.3048)
			(stroke
				(width 0.1)
				(type default)
			)
			(layer "B.Fab")
		)
		(fp_line
			(start -0.67945 -0.3048)
			(end -0.67945 0.3048)
			(stroke
				(width 0.1)
				(type default)
			)
			(layer "B.Fab")
		)
		(pad "1" smd circle
			(at 0.40005 0)
			(size 0 0)
			(layers "B.Cu" "B.Mask" "B.Paste")
			(net "P3V3_AUX")
		)
		(pad "2" smd circle
			(at -0.40005 0)
			(size 0 0)
			(layers "B.Cu" "B.Mask" "B.Paste")
			(net "GND")
		)
	)
	(footprint ""
		(layer "B.Cu")
		(at 407.91892 -35.187128)
		(property "Reference" "ME4"
			(at 9.652 -9.540748 0)
			(unlocked yes)
			(layer "B.SilkS")
			(effects
				(font
					(size 0.7874 0.5842)
					(thickness 0.1524)
				)
				(justify left mirror)
			)
		)
		(property "Value" ""
			(at 0 0 0)
			(layer "B.Fab")
			(effects
				(font
					(size 1.27 1.27)
				)
				(justify mirror)
			)
		)
		(duplicate_pad_numbers_are_jumpers no)
	)
	(footprint ""
		(layer "B.Cu")
		(at 228.71684 -125.202188 -90)
		(property "Reference" "C1409"
			(at 0 0 90)
			(layer "B.SilkS")
			(hide yes)
			(effects
				(font
					(size 1.27 1.27)
				)
				(justify mirror)
			)
		)
		(property "Value" ""
			(at 0 0 90)
			(layer "B.Fab")
			(effects
				(font
					(size 1.27 1.27)
				)
				(justify mirror)
			)
		)
		(duplicate_pad_numbers_are_jumpers no)
		(fp_line
			(start -1.2954 0.5842)
			(end 1.2954 0.5842)
			(stroke
				(width 0.1524)
				(type default)
			)
			(layer "B.SilkS")
		)
		(fp_line
			(start 1.2954 0.5842)
			(end 1.2954 -0.5842)
			(stroke
				(width 0.1524)
				(type default)
			)
			(layer "B.SilkS")
		)
		(fp_line
			(start -1.2954 -0.5842)
			(end -1.2954 0.5842)
			(stroke
				(width 0.1524)
				(type default)
			)
			(layer "B.SilkS")
		)
		(fp_line
			(start 0 -0.5842)
			(end 0 0.5842)
			(stroke
				(width 0.1524)
				(type default)
			)
			(layer "B.SilkS")
		)
		(fp_line
			(start 1.2954 -0.5842)
			(end -1.2954 -0.5842)
			(stroke
				(width 0.1524)
				(type default)
			)
			(layer "B.SilkS")
		)
		(fp_line
			(start -0.8636 0.4572)
			(end 0.8636 0.4572)
			(stroke
				(width 0.1)
				(type default)
			)
			(layer "B.Fab")
		)
		(fp_line
			(start 0.8636 0.4572)
			(end 0.8636 0.4064)
			(stroke
				(width 0.1)
				(type default)
			)
			(layer "B.Fab")
		)
		(fp_line
			(start -1.1938 0.4064)
			(end -0.8636 0.4064)
			(stroke
				(width 0.1)
				(type default)
			)
			(layer "B.Fab")
		)
		(fp_line
			(start -0.8636 0.4064)
			(end -0.8636 0.4572)
			(stroke
				(width 0.1)
				(type default)
			)
			(layer "B.Fab")
		)
		(fp_line
			(start 0.8636 0.4064)
			(end 1.1938 0.4064)
			(stroke
				(width 0.1)
				(type default)
			)
			(layer "B.Fab")
		)
		(fp_line
			(start 1.1938 0.4064)
			(end 1.1938 -0.4064)
			(stroke
				(width 0.1)
				(type default)
			)
			(layer "B.Fab")
		)
		(fp_line
			(start -1.1938 -0.4064)
			(end -1.1938 0.4064)
			(stroke
				(width 0.1)
				(type default)
			)
			(layer "B.Fab")
		)
		(fp_line
			(start -0.8636 -0.4064)
			(end -1.1938 -0.4064)
			(stroke
				(width 0.1)
				(type default)
			)
			(layer "B.Fab")
		)
		(fp_line
			(start 0.8636 -0.4064)
			(end 0.8636 -0.4572)
			(stroke
				(width 0.1)
				(type default)
			)
			(layer "B.Fab")
		)
		(fp_line
			(start 1.1938 -0.4064)
			(end 0.8636 -0.4064)
			(stroke
				(width 0.1)
				(type default)
			)
			(layer "B.Fab")
		)
		(fp_line
			(start -0.8636 -0.4572)
			(end -0.8636 -0.4064)
			(stroke
				(width 0.1)
				(type default)
			)
			(layer "B.Fab")
		)
		(fp_line
			(start 0.8636 -0.4572)
			(end -0.8636 -0.4572)
			(stroke
				(width 0.1)
				(type default)
			)
			(layer "B.Fab")
		)
		(pad "1" smd rect
			(at 0.7366 0 180)
			(size 0.7112 0.8128)
			(layers "B.Cu" "B.Mask" "B.Paste")
			(net "P3V3_DB2000_VDD")
		)
		(pad "2" smd rect
			(at -0.7366 0 180)
			(size 0.7112 0.8128)
			(layers "B.Cu" "B.Mask" "B.Paste")
			(net "GND")
		)
	)
	(footprint ""
		(layer "B.Cu")
		(at 373.112538 -187.99429 90)
		(property "Reference" "R910"
			(at 0 0 90)
			(layer "B.SilkS")
			(hide yes)
			(effects
				(font
					(size 1.27 1.27)
				)
				(justify mirror)
			)
		)
		(property "Value" ""
			(at 0 0 90)
			(layer "B.Fab")
			(effects
				(font
					(size 1.27 1.27)
				)
				(justify mirror)
			)
		)
		(duplicate_pad_numbers_are_jumpers no)
		(fp_line
			(start 0.7874 -0.4064)
			(end -0.7874 -0.4064)
			(stroke
				(width 0.1524)
				(type default)
			)
			(layer "B.SilkS")
		)
		(fp_line
			(start -0.7874 -0.4064)
			(end -0.7874 0.4064)
			(stroke
				(width 0.1524)
				(type default)
			)
			(layer "B.SilkS")
		)
		(fp_line
			(start 0.7874 0.4064)
			(end 0.7874 -0.4064)
			(stroke
				(width 0.1524)
				(type default)
			)
			(layer "B.SilkS")
		)
		(fp_line
			(start -0.7874 0.4064)
			(end 0.7874 0.4064)
			(stroke
				(width 0.1524)
				(type default)
			)
			(layer "B.SilkS")
		)
		(fp_line
			(start 0.67945 -0.305054)
			(end 0.12065 -0.305054)
			(stroke
				(width 0.1)
				(type default)
			)
			(layer "B.Fab")
		)
		(fp_line
			(start 0.12065 -0.305054)
			(end 0.12065 -0.2794)
			(stroke
				(width 0.1)
				(type default)
			)
			(layer "B.Fab")
		)
		(fp_line
			(start -0.12065 -0.3048)
			(end -0.67945 -0.3048)
			(stroke
				(width 0.1)
				(type default)
			)
			(layer "B.Fab")
		)
		(fp_line
			(start -0.67945 -0.3048)
			(end -0.67945 0.3048)
			(stroke
				(width 0.1)
				(type default)
			)
			(layer "B.Fab")
		)
		(fp_line
			(start 0.12065 -0.2794)
			(end -0.12065 -0.2794)
			(stroke
				(width 0.1)
				(type default)
			)
			(layer "B.Fab")
		)
		(fp_line
			(start -0.12065 -0.2794)
			(end -0.12065 -0.3048)
			(stroke
				(width 0.1)
				(type default)
			)
			(layer "B.Fab")
		)
		(fp_line
			(start 0.12065 0.2794)
			(end 0.12065 0.3048)
			(stroke
				(width 0.1)
				(type default)
			)
			(layer "B.Fab")
		)
		(fp_line
			(start -0.120396 0.2794)
			(end 0.12065 0.2794)
			(stroke
				(width 0.1)
				(type default)
			)
			(layer "B.Fab")
		)
		(fp_line
			(start 0.67945 0.3048)
			(end 0.67945 -0.305054)
			(stroke
				(width 0.1)
				(type default)
			)
			(layer "B.Fab")
		)
		(fp_line
			(start 0.12065 0.3048)
			(end 0.67945 0.3048)
			(stroke
				(width 0.1)
				(type default)
			)
			(layer "B.Fab")
		)
		(fp_line
			(start -0.120396 0.3048)
			(end -0.120396 0.2794)
			(stroke
				(width 0.1)
				(type default)
			)
			(layer "B.Fab")
		)
		(fp_line
			(start -0.67945 0.3048)
			(end -0.120396 0.3048)
			(stroke
				(width 0.1)
				(type default)
			)
			(layer "B.Fab")
		)
		(pad "1" smd circle
			(at 0.40005 0 270)
			(size 0 0)
			(layers "B.Cu" "B.Mask" "B.Paste")
			(net "PVNN_TERM_CPU0")
		)
		(pad "2" smd circle
			(at -0.40005 0 270)
			(size 0 0)
			(layers "B.Cu" "B.Mask" "B.Paste")
			(net "SMB_PEHPCPU0_GTL_R_SCL")
		)
	)
	(footprint ""
		(layer "B.Cu")
		(at 324.423278 -186.68619 -90)
		(property "Reference" "R275"
			(at 0 0 90)
			(layer "B.SilkS")
			(hide yes)
			(effects
				(font
					(size 1.27 1.27)
				)
				(justify mirror)
			)
		)
		(property "Value" ""
			(at 0 0 90)
			(layer "B.Fab")
			(effects
				(font
					(size 1.27 1.27)
				)
				(justify mirror)
			)
		)
		(duplicate_pad_numbers_are_jumpers no)
		(fp_line
			(start -0.7874 0.4064)
			(end 0.7874 0.4064)
			(stroke
				(width 0.1524)
				(type default)
			)
			(layer "B.SilkS")
		)
		(fp_line
			(start 0.7874 0.4064)
			(end 0.7874 -0.4064)
			(stroke
				(width 0.1524)
				(type default)
			)
			(layer "B.SilkS")
		)
		(fp_line
			(start -0.7874 -0.4064)
			(end -0.7874 0.4064)
			(stroke
				(width 0.1524)
				(type default)
			)
			(layer "B.SilkS")
		)
		(fp_line
			(start 0.7874 -0.4064)
			(end -0.7874 -0.4064)
			(stroke
				(width 0.1524)
				(type default)
			)
			(layer "B.SilkS")
		)
		(fp_line
			(start -0.67945 0.3048)
			(end -0.120396 0.3048)
			(stroke
				(width 0.1)
				(type default)
			)
			(layer "B.Fab")
		)
		(fp_line
			(start -0.120396 0.3048)
			(end -0.120396 0.2794)
			(stroke
				(width 0.1)
				(type default)
			)
			(layer "B.Fab")
		)
		(fp_line
			(start 0.12065 0.3048)
			(end 0.67945 0.3048)
			(stroke
				(width 0.1)
				(type default)
			)
			(layer "B.Fab")
		)
		(fp_line
			(start 0.67945 0.3048)
			(end 0.67945 -0.305054)
			(stroke
				(width 0.1)
				(type default)
			)
			(layer "B.Fab")
		)
		(fp_line
			(start -0.120396 0.2794)
			(end 0.12065 0.2794)
			(stroke
				(width 0.1)
				(type default)
			)
			(layer "B.Fab")
		)
		(fp_line
			(start 0.12065 0.2794)
			(end 0.12065 0.3048)
			(stroke
				(width 0.1)
				(type default)
			)
			(layer "B.Fab")
		)
		(fp_line
			(start -0.12065 -0.2794)
			(end -0.12065 -0.3048)
			(stroke
				(width 0.1)
				(type default)
			)
			(layer "B.Fab")
		)
		(fp_line
			(start 0.12065 -0.2794)
			(end -0.12065 -0.2794)
			(stroke
				(width 0.1)
				(type default)
			)
			(layer "B.Fab")
		)
		(fp_line
			(start -0.67945 -0.3048)
			(end -0.67945 0.3048)
			(stroke
				(width 0.1)
				(type default)
			)
			(layer "B.Fab")
		)
		(fp_line
			(start -0.12065 -0.3048)
			(end -0.67945 -0.3048)
			(stroke
				(width 0.1)
				(type default)
			)
			(layer "B.Fab")
		)
		(fp_line
			(start 0.12065 -0.305054)
			(end 0.12065 -0.2794)
			(stroke
				(width 0.1)
				(type default)
			)
			(layer "B.Fab")
		)
		(fp_line
			(start 0.67945 -0.305054)
			(end 0.12065 -0.305054)
			(stroke
				(width 0.1)
				(type default)
			)
			(layer "B.Fab")
		)
		(pad "1" smd circle
			(at 0.40005 0 90)
			(size 0 0)
			(layers "B.Cu" "B.Mask" "B.Paste")
			(net "PVNN_TERM_CPU0")
		)
		(pad "2" smd circle
			(at -0.40005 0 90)
			(size 0 0)
			(layers "B.Cu" "B.Mask" "B.Paste")
			(net "PU_CPU0_TXT_AGENT")
		)
	)
)
